(kicad_pcb
	(version 20260206)
	(generator "pcbnew")
	(generator_version "10.0")
	(general
		(thickness 1.6)
		(legacy_teardrops no)
	)
	(paper "A4")
	(title_block
		(title "Bryce Canyon_R.DPB_16317-1_OCP.brd")
		(comment 1 "Bryce Canyon / footprints 2079-2086 of 2099")
	)
	(layers
		(0 "F.Cu" signal "TOP")
		(4 "In1.Cu" signal "L2GND")
		(6 "In2.Cu" signal "L3")
		(8 "In3.Cu" signal "L4VCC")
		(10 "In4.Cu" signal "L5VCC")
		(12 "In5.Cu" signal "L6")
		(14 "In6.Cu" signal "L7GND")
		(2 "B.Cu" signal "BOTTOM")
		(9 "F.Adhes" user "F.Adhesive")
		(11 "B.Adhes" user "B.Adhesive")
		(13 "F.Paste" user "Package Geometry/Pastemask Top")
		(15 "B.Paste" user "Package Geometry/Pastemask Bottom")
		(5 "F.SilkS" user "Ref Des/Silkscreen Top")
		(7 "B.SilkS" user "Ref Des/Silkscreen Bottom")
		(1 "F.Mask" user "Board Geometry/Soldermask Top")
		(3 "B.Mask" user "Board Geometry/Soldermask Bottom")
		(17 "Dwgs.User" user "User.Drawings")
		(19 "Cmts.User" user "User.Comments")
		(21 "Eco1.User" user "User.Eco1")
		(23 "Eco2.User" user "User.Eco2")
		(25 "Edge.Cuts" user "Board Geometry/Outline")
		(27 "Margin" user)
		(31 "F.CrtYd" user "Package Geometry/Place Bound Top")
		(29 "B.CrtYd" user "Package Geometry/Place Bound Bottom")
		(35 "F.Fab" user "Ref Des/Assembly Top")
		(33 "B.Fab" user "Ref Des/Assembly Bottom")
	)
	(footprint ""
		(layer "B.Cu")
		(at 246.3546 -286.9692 180)
		(property "Reference" "C698"
			(at 0 0 0)
			(layer "B.SilkS")
			(hide yes)
			(effects
				(font
					(size 1.27 1.27)
				)
				(justify mirror)
			)
		)
		(property "Value" "SCD1U25V3KX-GP"
			(at 0 -2.8194 180)
			(unlocked yes)
			(layer "B.Fab")
			(hide yes)
			(effects
				(font
					(size 1.016 1.016)
					(thickness 0.1524)
				)
				(justify mirror)
			)
		)
		(property "Device Type" "C603H36"
			(at 0 -4.3434 180)
			(unlocked yes)
			(layer "B.Fab")
			(hide yes)
			(effects
				(font
					(size 1.016 1.016)
					(thickness 0.1524)
				)
				(justify mirror)
			)
		)
		(duplicate_pad_numbers_are_jumpers no)
		(fp_line
			(start -0.508 0)
			(end 0.508 0)
			(stroke
				(width 0.2032)
				(type default)
			)
			(layer "B.SilkS")
		)
		(fp_rect
			(start 0.5842 1.3335)
			(end -0.5842 -1.3335)
			(stroke
				(width 0)
				(type default)
			)
			(fill no)
			(layer "B.CrtYd")
		)
		(fp_rect
			(start 0.5842 1.3335)
			(end -0.5842 -1.3335)
			(stroke
				(width 0)
				(type default)
			)
			(fill no)
			(layer "B.Fab")
		)
		(pad "1" smd custom
			(at 0 -0.762)
			(size 0.2159 0.2159)
			(layers "B.Cu" "B.Mask" "B.Paste")
			(net "P3V3_STBY_B")
			(options
				(clearance outline)
				(anchor circle)
			)
			(primitives
				(gr_poly
					(pts
						(arc
							(start -0.3302 0.4318)
							(mid -0.402042 0.402042)
							(end -0.4318 0.3302)
						)
						(arc
							(start -0.4318 -0.3302)
							(mid -0.402042 -0.402042)
							(end -0.3302 -0.4318)
						)
						(arc
							(start 0.3302 -0.4318)
							(mid 0.402042 -0.402042)
							(end 0.4318 -0.3302)
						)
						(arc
							(start 0.4318 0.3302)
							(mid 0.402042 0.402042)
							(end 0.3302 0.4318)
						)
					)
					(width 0)
					(fill yes)
				)
			)
		)
		(pad "2" smd custom
			(at 0 0.762)
			(size 0.2159 0.2159)
			(layers "B.Cu" "B.Mask" "B.Paste")
			(net "P3V3_STBY_VFB_R")
			(options
				(clearance outline)
				(anchor circle)
			)
			(primitives
				(gr_poly
					(pts
						(arc
							(start -0.3302 0.4318)
							(mid -0.402042 0.402042)
							(end -0.4318 0.3302)
						)
						(arc
							(start -0.4318 -0.3302)
							(mid -0.402042 -0.402042)
							(end -0.3302 -0.4318)
						)
						(arc
							(start 0.3302 -0.4318)
							(mid 0.402042 -0.402042)
							(end 0.4318 -0.3302)
						)
						(arc
							(start 0.4318 0.3302)
							(mid 0.402042 0.402042)
							(end 0.3302 0.4318)
						)
					)
					(width 0)
					(fill yes)
				)
			)
		)
	)
	(footprint ""
		(layer "B.Cu")
		(at 40.78986 -114.246406 90)
		(property "Reference" "C645"
			(at 0 0 90)
			(layer "B.SilkS")
			(hide yes)
			(effects
				(font
					(size 1.27 1.27)
				)
				(justify mirror)
			)
		)
		(property "Value" "SC1U16V3KX-5GP"
			(at 0 -2.8194 90)
			(unlocked yes)
			(layer "B.Fab")
			(hide yes)
			(effects
				(font
					(size 1.016 1.016)
					(thickness 0.1524)
				)
				(justify mirror)
			)
		)
		(property "Device Type" "C603H36"
			(at 0 -4.3434 90)
			(unlocked yes)
			(layer "B.Fab")
			(hide yes)
			(effects
				(font
					(size 1.016 1.016)
					(thickness 0.1524)
				)
				(justify mirror)
			)
		)
		(duplicate_pad_numbers_are_jumpers no)
		(fp_line
			(start -0.508 0)
			(end 0.508 0)
			(stroke
				(width 0.2032)
				(type default)
			)
			(layer "B.SilkS")
		)
		(fp_rect
			(start 0.5842 1.3335)
			(end -0.5842 -1.3335)
			(stroke
				(width 0)
				(type default)
			)
			(fill no)
			(layer "B.CrtYd")
		)
		(fp_rect
			(start 0.5842 1.3335)
			(end -0.5842 -1.3335)
			(stroke
				(width 0)
				(type default)
			)
			(fill no)
			(layer "B.Fab")
		)
		(pad "1" smd custom
			(at 0 -0.762 270)
			(size 0.2159 0.2159)
			(layers "B.Cu" "B.Mask" "B.Paste")
			(net "GND")
			(options
				(clearance outline)
				(anchor circle)
			)
			(primitives
				(gr_poly
					(pts
						(arc
							(start -0.3302 0.4318)
							(mid -0.402042 0.402042)
							(end -0.4318 0.3302)
						)
						(arc
							(start -0.4318 -0.3302)
							(mid -0.402042 -0.402042)
							(end -0.3302 -0.4318)
						)
						(arc
							(start 0.3302 -0.4318)
							(mid 0.402042 -0.402042)
							(end 0.4318 -0.3302)
						)
						(arc
							(start 0.4318 0.3302)
							(mid 0.402042 0.402042)
							(end 0.3302 0.4318)
						)
					)
					(width 0)
					(fill yes)
				)
			)
		)
		(pad "2" smd custom
			(at 0 0.762 270)
			(size 0.2159 0.2159)
			(layers "B.Cu" "B.Mask" "B.Paste")
			(net "P5V_B_2_VREG")
			(options
				(clearance outline)
				(anchor circle)
			)
			(primitives
				(gr_poly
					(pts
						(arc
							(start -0.3302 0.4318)
							(mid -0.402042 0.402042)
							(end -0.4318 0.3302)
						)
						(arc
							(start -0.4318 -0.3302)
							(mid -0.402042 -0.402042)
							(end -0.3302 -0.4318)
						)
						(arc
							(start 0.3302 -0.4318)
							(mid 0.402042 -0.402042)
							(end 0.4318 -0.3302)
						)
						(arc
							(start 0.4318 0.3302)
							(mid 0.402042 0.402042)
							(end 0.3302 0.4318)
						)
					)
					(width 0)
					(fill yes)
				)
			)
		)
	)
	(footprint ""
		(layer "B.Cu")
		(at 467.903814 -229.093776 180)
		(property "Reference" "C664"
			(at 0 0 0)
			(layer "B.SilkS")
			(hide yes)
			(effects
				(font
					(size 1.27 1.27)
				)
				(justify mirror)
			)
		)
		(property "Value" "SCD1U50V3KX-GP"
			(at 0 -2.8194 180)
			(unlocked yes)
			(layer "B.Fab")
			(hide yes)
			(effects
				(font
					(size 1.016 1.016)
					(thickness 0.1524)
				)
				(justify mirror)
			)
		)
		(property "Device Type" "C603H36"
			(at 0 -4.3434 180)
			(unlocked yes)
			(layer "B.Fab")
			(hide yes)
			(effects
				(font
					(size 1.016 1.016)
					(thickness 0.1524)
				)
				(justify mirror)
			)
		)
		(duplicate_pad_numbers_are_jumpers no)
		(fp_line
			(start -0.508 0)
			(end 0.508 0)
			(stroke
				(width 0.2032)
				(type default)
			)
			(layer "B.SilkS")
		)
		(fp_rect
			(start 0.5842 1.3335)
			(end -0.5842 -1.3335)
			(stroke
				(width 0)
				(type default)
			)
			(fill no)
			(layer "B.CrtYd")
		)
		(fp_rect
			(start 0.5842 1.3335)
			(end -0.5842 -1.3335)
			(stroke
				(width 0)
				(type default)
			)
			(fill no)
			(layer "B.Fab")
		)
		(pad "1" smd custom
			(at 0 -0.762)
			(size 0.2159 0.2159)
			(layers "B.Cu" "B.Mask" "B.Paste")
			(net "P5V_B_3")
			(options
				(clearance outline)
				(anchor circle)
			)
			(primitives
				(gr_poly
					(pts
						(arc
							(start -0.3302 0.4318)
							(mid -0.402042 0.402042)
							(end -0.4318 0.3302)
						)
						(arc
							(start -0.4318 -0.3302)
							(mid -0.402042 -0.402042)
							(end -0.3302 -0.4318)
						)
						(arc
							(start 0.3302 -0.4318)
							(mid 0.402042 -0.402042)
							(end 0.4318 -0.3302)
						)
						(arc
							(start 0.4318 0.3302)
							(mid 0.402042 0.402042)
							(end 0.3302 0.4318)
						)
					)
					(width 0)
					(fill yes)
				)
			)
		)
		(pad "2" smd custom
			(at 0 0.762)
			(size 0.2159 0.2159)
			(layers "B.Cu" "B.Mask" "B.Paste")
			(net "P5V_B_3_LL_R")
			(options
				(clearance outline)
				(anchor circle)
			)
			(primitives
				(gr_poly
					(pts
						(arc
							(start -0.3302 0.4318)
							(mid -0.402042 0.402042)
							(end -0.4318 0.3302)
						)
						(arc
							(start -0.4318 -0.3302)
							(mid -0.402042 -0.402042)
							(end -0.3302 -0.4318)
						)
						(arc
							(start 0.3302 -0.4318)
							(mid 0.402042 -0.402042)
							(end 0.4318 -0.3302)
						)
						(arc
							(start 0.4318 0.3302)
							(mid 0.402042 0.402042)
							(end 0.3302 0.4318)
						)
					)
					(width 0)
					(fill yes)
				)
			)
		)
	)
	(footprint ""
		(layer "B.Cu")
		(at 425.922186 -109.780578 90)
		(property "Reference" "L7"
			(at 0 0 90)
			(layer "B.SilkS")
			(hide yes)
			(effects
				(font
					(size 1.27 1.27)
				)
				(justify mirror)
			)
		)
		(property "Value" "BLM21PG220SN1DGP"
			(at -0.0254 -5.6896 90)
			(unlocked yes)
			(layer "B.Fab")
			(hide yes)
			(effects
				(font
					(size 1.016 1.016)
					(thickness 0.1524)
				)
				(justify mirror)
			)
		)
		(property "Device Type" "L20125H42"
			(at -0.0254 -7.5946 90)
			(unlocked yes)
			(layer "B.Fab")
			(hide yes)
			(effects
				(font
					(size 1.016 1.016)
					(thickness 0.1524)
				)
				(justify mirror)
			)
		)
		(duplicate_pad_numbers_are_jumpers no)
		(fp_line
			(start 0.9144 -1.7018)
			(end 0.9144 1.7018)
			(stroke
				(width 0.1524)
				(type default)
			)
			(layer "B.SilkS")
		)
		(fp_line
			(start -0.9144 -1.7018)
			(end 0.9144 -1.7018)
			(stroke
				(width 0.1524)
				(type default)
			)
			(layer "B.SilkS")
		)
		(fp_line
			(start 0.9144 1.7018)
			(end -0.9144 1.7018)
			(stroke
				(width 0.1524)
				(type default)
			)
			(layer "B.SilkS")
		)
		(fp_line
			(start -0.9144 1.7018)
			(end -0.9144 -1.7018)
			(stroke
				(width 0.1524)
				(type default)
			)
			(layer "B.SilkS")
		)
		(fp_rect
			(start 1.0033 1.778)
			(end -1.0033 -1.778)
			(stroke
				(width 0)
				(type default)
			)
			(fill no)
			(layer "B.CrtYd")
		)
		(fp_poly
			(pts
				(xy 1.0033 -1.778) (xy -1.0033 -1.778) (xy -1.0033 1.778) (xy 1.0033 1.778)
			)
			(stroke
				(width 0)
				(type default)
			)
			(fill no)
			(layer "B.Fab")
		)
		(pad "1" smd rect
			(at 0 -0.9652 270)
			(size 1.397 1.143)
			(layers "B.Cu" "B.Mask" "B.Paste")
			(net "P12V_B")
		)
		(pad "2" smd rect
			(at 0 0.9652 270)
			(size 1.397 1.143)
			(layers "B.Cu" "B.Mask" "B.Paste")
			(net "P12V_B_4_VIN_U34")
		)
	)
	(footprint ""
		(layer "B.Cu")
		(at 260.239002 -283.006546 90)
		(property "Reference" "C696"
			(at 0 0 90)
			(layer "B.SilkS")
			(hide yes)
			(effects
				(font
					(size 1.27 1.27)
				)
				(justify mirror)
			)
		)
		(property "Value" "SC1U16V3KX-5GP"
			(at 0 -2.8194 90)
			(unlocked yes)
			(layer "B.Fab")
			(hide yes)
			(effects
				(font
					(size 1.016 1.016)
					(thickness 0.1524)
				)
				(justify mirror)
			)
		)
		(property "Device Type" "C603H36"
			(at 0 -4.3434 90)
			(unlocked yes)
			(layer "B.Fab")
			(hide yes)
			(effects
				(font
					(size 1.016 1.016)
					(thickness 0.1524)
				)
				(justify mirror)
			)
		)
		(duplicate_pad_numbers_are_jumpers no)
		(fp_line
			(start -0.508 0)
			(end 0.508 0)
			(stroke
				(width 0.2032)
				(type default)
			)
			(layer "B.SilkS")
		)
		(fp_rect
			(start 0.5842 1.3335)
			(end -0.5842 -1.3335)
			(stroke
				(width 0)
				(type default)
			)
			(fill no)
			(layer "B.CrtYd")
		)
		(fp_rect
			(start 0.5842 1.3335)
			(end -0.5842 -1.3335)
			(stroke
				(width 0)
				(type default)
			)
			(fill no)
			(layer "B.Fab")
		)
		(pad "1" smd custom
			(at 0 -0.762 270)
			(size 0.2159 0.2159)
			(layers "B.Cu" "B.Mask" "B.Paste")
			(net "P3V3_STBY_VRG5")
			(options
				(clearance outline)
				(anchor circle)
			)
			(primitives
				(gr_poly
					(pts
						(arc
							(start -0.3302 0.4318)
							(mid -0.402042 0.402042)
							(end -0.4318 0.3302)
						)
						(arc
							(start -0.4318 -0.3302)
							(mid -0.402042 -0.402042)
							(end -0.3302 -0.4318)
						)
						(arc
							(start 0.3302 -0.4318)
							(mid 0.402042 -0.402042)
							(end 0.4318 -0.3302)
						)
						(arc
							(start 0.4318 0.3302)
							(mid 0.402042 0.402042)
							(end 0.3302 0.4318)
						)
					)
					(width 0)
					(fill yes)
				)
			)
		)
		(pad "2" smd custom
			(at 0 0.762 270)
			(size 0.2159 0.2159)
			(layers "B.Cu" "B.Mask" "B.Paste")
			(net "GND")
			(options
				(clearance outline)
				(anchor circle)
			)
			(primitives
				(gr_poly
					(pts
						(arc
							(start -0.3302 0.4318)
							(mid -0.402042 0.402042)
							(end -0.4318 0.3302)
						)
						(arc
							(start -0.4318 -0.3302)
							(mid -0.402042 -0.402042)
							(end -0.3302 -0.4318)
						)
						(arc
							(start 0.3302 -0.4318)
							(mid 0.402042 -0.402042)
							(end 0.4318 -0.3302)
						)
						(arc
							(start 0.4318 0.3302)
							(mid 0.402042 0.402042)
							(end 0.3302 0.4318)
						)
					)
					(width 0)
					(fill yes)
				)
			)
		)
	)
	(footprint ""
		(layer "B.Cu")
		(at 30.920944 -229.101396 180)
		(property "Reference" "R1103"
			(at 0 0 0)
			(layer "B.SilkS")
			(hide yes)
			(effects
				(font
					(size 1.27 1.27)
				)
				(justify mirror)
			)
		)
		(property "Value" "2K7R2F-GP"
			(at -0.064008 -3.993896 180)
			(unlocked yes)
			(layer "B.Fab")
			(hide yes)
			(effects
				(font
					(size 1.016 1.016)
					(thickness 0.1524)
				)
				(justify mirror)
			)
		)
		(property "Device Type" "R402H16"
			(at -0.064008 -5.517896 180)
			(unlocked yes)
			(layer "B.Fab")
			(hide yes)
			(effects
				(font
					(size 1.016 1.016)
					(thickness 0.1524)
				)
				(justify mirror)
			)
		)
		(duplicate_pad_numbers_are_jumpers no)
		(fp_line
			(start 0.508 -0.9398)
			(end 0.508 0.9398)
			(stroke
				(width 0.1524)
				(type default)
			)
			(layer "B.SilkS")
		)
		(fp_line
			(start -0.508 -0.9398)
			(end 0.508 -0.9398)
			(stroke
				(width 0.1524)
				(type default)
			)
			(layer "B.SilkS")
		)
		(fp_rect
			(start 0.508 0.9398)
			(end -0.508 -0.9398)
			(stroke
				(width 0)
				(type default)
			)
			(fill no)
			(layer "B.CrtYd")
		)
		(fp_rect
			(start 0.508 0.9398)
			(end -0.508 -0.9398)
			(stroke
				(width 0)
				(type default)
			)
			(fill no)
			(layer "B.Fab")
		)
		(pad "1" smd custom
			(at 0 -0.4445)
			(size 0.1397 0.1397)
			(layers "B.Cu" "B.Mask" "B.Paste")
			(net "P5V_B_1_LL")
			(options
				(clearance outline)
				(anchor circle)
			)
			(primitives
				(gr_poly
					(pts
						(arc
							(start -0.1778 0.2794)
							(mid -0.249642 0.249642)
							(end -0.2794 0.1778)
						)
						(arc
							(start -0.2794 -0.1778)
							(mid -0.249642 -0.249642)
							(end -0.1778 -0.2794)
						)
						(arc
							(start 0.1778 -0.2794)
							(mid 0.249642 -0.249642)
							(end 0.2794 -0.1778)
						)
						(arc
							(start 0.2794 0.1778)
							(mid 0.249642 0.249642)
							(end 0.1778 0.2794)
						)
					)
					(width 0)
					(fill yes)
				)
			)
		)
		(pad "2" smd custom
			(at 0 0.4445)
			(size 0.1397 0.1397)
			(layers "B.Cu" "B.Mask" "B.Paste")
			(net "P5V_B_1_LL_R")
			(options
				(clearance outline)
				(anchor circle)
			)
			(primitives
				(gr_poly
					(pts
						(arc
							(start -0.1778 0.2794)
							(mid -0.249642 0.249642)
							(end -0.2794 0.1778)
						)
						(arc
							(start -0.2794 -0.1778)
							(mid -0.249642 -0.249642)
							(end -0.1778 -0.2794)
						)
						(arc
							(start 0.1778 -0.2794)
							(mid 0.249642 -0.249642)
							(end 0.2794 -0.1778)
						)
						(arc
							(start 0.2794 0.1778)
							(mid 0.249642 0.249642)
							(end 0.1778 0.2794)
						)
					)
					(width 0)
					(fill yes)
				)
			)
		)
	)
	(footprint ""
		(layer "B.Cu")
		(at 260.7818 -287.5026)
		(property "Reference" "R1177"
			(at 0 0 0)
			(layer "B.SilkS")
			(hide yes)
			(effects
				(font
					(size 1.27 1.27)
				)
				(justify mirror)
			)
		)
		(property "Value" "33KR2J-3-GP"
			(at -0.064008 -3.993896 0)
			(unlocked yes)
			(layer "B.Fab")
			(hide yes)
			(effects
				(font
					(size 1.016 1.016)
					(thickness 0.1524)
				)
				(justify mirror)
			)
		)
		(property "Device Type" "R402H16"
			(at -0.064008 -5.517896 0)
			(unlocked yes)
			(layer "B.Fab")
			(hide yes)
			(effects
				(font
					(size 1.016 1.016)
					(thickness 0.1524)
				)
				(justify mirror)
			)
		)
		(duplicate_pad_numbers_are_jumpers no)
		(fp_line
			(start -0.508 -0.9398)
			(end 0.508 -0.9398)
			(stroke
				(width 0.1524)
				(type default)
			)
			(layer "B.SilkS")
		)
		(fp_line
			(start 0.508 -0.9398)
			(end 0.508 0.9398)
			(stroke
				(width 0.1524)
				(type default)
			)
			(layer "B.SilkS")
		)
		(fp_rect
			(start 0.508 0.9398)
			(end -0.508 -0.9398)
			(stroke
				(width 0)
				(type default)
			)
			(fill no)
			(layer "B.CrtYd")
		)
		(fp_rect
			(start 0.508 0.9398)
			(end -0.508 -0.9398)
			(stroke
				(width 0)
				(type default)
			)
			(fill no)
			(layer "B.Fab")
		)
		(pad "1" smd custom
			(at 0 -0.4445 180)
			(size 0.1397 0.1397)
			(layers "B.Cu" "B.Mask" "B.Paste")
			(net "P3V3_STBY_CC_R")
			(options
				(clearance outline)
				(anchor circle)
			)
			(primitives
				(gr_poly
					(pts
						(arc
							(start -0.1778 0.2794)
							(mid -0.249642 0.249642)
							(end -0.2794 0.1778)
						)
						(arc
							(start -0.2794 -0.1778)
							(mid -0.249642 -0.249642)
							(end -0.1778 -0.2794)
						)
						(arc
							(start 0.1778 -0.2794)
							(mid 0.249642 -0.249642)
							(end 0.2794 -0.1778)
						)
						(arc
							(start 0.2794 0.1778)
							(mid 0.249642 0.249642)
							(end 0.1778 0.2794)
						)
					)
					(width 0)
					(fill yes)
				)
			)
		)
		(pad "2" smd custom
			(at 0 0.4445 180)
			(size 0.1397 0.1397)
			(layers "B.Cu" "B.Mask" "B.Paste")
			(net "P3V3_STBY_VFB")
			(options
				(clearance outline)
				(anchor circle)
			)
			(primitives
				(gr_poly
					(pts
						(arc
							(start -0.1778 0.2794)
							(mid -0.249642 0.249642)
							(end -0.2794 0.1778)
						)
						(arc
							(start -0.2794 -0.1778)
							(mid -0.249642 -0.249642)
							(end -0.1778 -0.2794)
						)
						(arc
							(start 0.1778 -0.2794)
							(mid 0.249642 -0.249642)
							(end 0.2794 -0.1778)
						)
						(arc
							(start 0.2794 0.1778)
							(mid 0.249642 0.249642)
							(end 0.1778 0.2794)
						)
					)
					(width 0)
					(fill yes)
				)
			)
		)
	)
	(footprint ""
		(layer "B.Cu")
		(at 40.28186 -115.897406 -90)
		(property "Reference" "C642"
			(at 0 0 90)
			(layer "B.SilkS")
			(hide yes)
			(effects
				(font
					(size 1.27 1.27)
				)
				(justify mirror)
			)
		)
		(property "Value" "SC4D7U25V5KX-1-GP"
			(at 0.0762 -6.1214 270)
			(unlocked yes)
			(layer "B.Fab")
			(hide yes)
			(effects
				(font
					(size 1.016 1.016)
					(thickness 0.1524)
				)
				(justify mirror)
			)
		)
		(property "Device Type" "C805H58"
			(at 0.0762 -8.1534 270)
			(unlocked yes)
			(layer "B.Fab")
			(hide yes)
			(effects
				(font
					(size 1.016 1.016)
					(thickness 0.1524)
				)
				(justify mirror)
			)
		)
		(duplicate_pad_numbers_are_jumpers no)
		(fp_line
			(start -0.635 0)
			(end 0.635 0)
			(stroke
				(width 0.508)
				(type default)
			)
			(layer "B.SilkS")
		)
		(fp_rect
			(start 0.9652 1.778)
			(end -0.9652 -1.778)
			(stroke
				(width 0)
				(type default)
			)
			(fill no)
			(layer "B.CrtYd")
		)
		(fp_poly
			(pts
				(xy 0.9652 -1.778) (xy -0.9652 -1.778) (xy -0.9652 1.778) (xy 0.9652 1.778)
			)
			(stroke
				(width 0)
				(type default)
			)
			(fill no)
			(layer "B.Fab")
		)
		(pad "1" smd rect
			(at 0 -0.9652 90)
			(size 1.397 1.143)
			(layers "B.Cu" "B.Mask" "B.Paste")
			(net "P12V_B_2_VDD_U32")
		)
		(pad "2" smd rect
			(at 0 0.9652 90)
			(size 1.397 1.143)
			(layers "B.Cu" "B.Mask" "B.Paste")
			(net "GND")
		)
	)
)
